(kicad_pcb
	(version 20260206)
	(generator "pcbnew")
	(generator_version "10.0")
	(general
		(thickness 1.6)
		(legacy_teardrops no)
	)
	(paper "A4")
	(title_block
		(title "12092022_DA0F0TMDCD0_F0T_Management_Board_D_brd_V3_OCP.brd")
		(comment 1 "Grand Teton / footprints 897-902 of 1440")
	)
	(layers
		(0 "F.Cu" signal "TOP")
		(4 "In1.Cu" signal "GND")
		(6 "In2.Cu" signal "IN1")
		(8 "In3.Cu" signal "GND1")
		(10 "In4.Cu" signal "IN2")
		(12 "In5.Cu" signal "VCC")
		(14 "In6.Cu" signal "VCC1")
		(16 "In7.Cu" signal "IN3")
		(18 "In8.Cu" signal "GND2")
		(20 "In9.Cu" signal "IN4")
		(22 "In10.Cu" signal "GND3")
		(2 "B.Cu" signal "BOTTOM")
		(9 "F.Adhes" user "F.Adhesive")
		(11 "B.Adhes" user "B.Adhesive")
		(13 "F.Paste" user "Package Geometry/Pastemask Top")
		(15 "B.Paste" user "Package Geometry/Pastemask Bottom")
		(5 "F.SilkS" user "Ref Des/Silkscreen Top")
		(7 "B.SilkS" user "Ref Des/Silkscreen Bottom")
		(1 "F.Mask" user "Board Geometry/Soldermask Top")
		(3 "B.Mask" user "Board Geometry/Soldermask Bottom")
		(17 "Dwgs.User" user "User.Drawings")
		(19 "Cmts.User" user "User.Comments")
		(21 "Eco1.User" user "User.Eco1")
		(23 "Eco2.User" user "User.Eco2")
		(25 "Edge.Cuts" user "Board Geometry/Outline")
		(27 "Margin" user)
		(31 "F.CrtYd" user "Package Geometry/Place Bound Top")
		(29 "B.CrtYd" user "Package Geometry/Place Bound Bottom")
		(35 "F.Fab" user "Ref Des/Assembly Top")
		(33 "B.Fab" user "Ref Des/Assembly Bottom")
	)
	(footprint ""
		(layer "B.Cu")
		(at 60.45835 -47.844964 90)
		(property "Reference" "C71"
			(at 0 0 90)
			(layer "B.SilkS")
			(hide yes)
			(effects
				(font
					(size 1.27 1.27)
				)
				(justify mirror)
			)
		)
		(property "Value" ""
			(at 0 0 90)
			(layer "B.Fab")
			(effects
				(font
					(size 1.27 1.27)
				)
				(justify mirror)
			)
		)
		(duplicate_pad_numbers_are_jumpers no)
		(fp_line
			(start 0.7874 -0.4064)
			(end -0.7874 -0.4064)
			(stroke
				(width 0.1524)
				(type default)
			)
			(layer "B.SilkS")
		)
		(fp_line
			(start -0.7874 -0.4064)
			(end -0.7874 0.4064)
			(stroke
				(width 0.1524)
				(type default)
			)
			(layer "B.SilkS")
		)
		(fp_line
			(start 0.7874 0.4064)
			(end 0.7874 -0.4064)
			(stroke
				(width 0.1524)
				(type default)
			)
			(layer "B.SilkS")
		)
		(fp_line
			(start -0.7874 0.4064)
			(end 0.7874 0.4064)
			(stroke
				(width 0.1524)
				(type default)
			)
			(layer "B.SilkS")
		)
		(fp_line
			(start 0.67945 -0.305054)
			(end 0.12065 -0.305054)
			(stroke
				(width 0.1)
				(type default)
			)
			(layer "B.Fab")
		)
		(fp_line
			(start 0.12065 -0.305054)
			(end 0.12065 -0.2794)
			(stroke
				(width 0.1)
				(type default)
			)
			(layer "B.Fab")
		)
		(fp_line
			(start -0.12065 -0.3048)
			(end -0.67945 -0.3048)
			(stroke
				(width 0.1)
				(type default)
			)
			(layer "B.Fab")
		)
		(fp_line
			(start -0.67945 -0.3048)
			(end -0.67945 0.3048)
			(stroke
				(width 0.1)
				(type default)
			)
			(layer "B.Fab")
		)
		(fp_line
			(start 0.12065 -0.2794)
			(end -0.12065 -0.2794)
			(stroke
				(width 0.1)
				(type default)
			)
			(layer "B.Fab")
		)
		(fp_line
			(start -0.12065 -0.2794)
			(end -0.12065 -0.3048)
			(stroke
				(width 0.1)
				(type default)
			)
			(layer "B.Fab")
		)
		(fp_line
			(start 0.12065 0.2794)
			(end 0.12065 0.3048)
			(stroke
				(width 0.1)
				(type default)
			)
			(layer "B.Fab")
		)
		(fp_line
			(start -0.120396 0.2794)
			(end 0.12065 0.2794)
			(stroke
				(width 0.1)
				(type default)
			)
			(layer "B.Fab")
		)
		(fp_line
			(start 0.67945 0.3048)
			(end 0.67945 -0.305054)
			(stroke
				(width 0.1)
				(type default)
			)
			(layer "B.Fab")
		)
		(fp_line
			(start 0.12065 0.3048)
			(end 0.67945 0.3048)
			(stroke
				(width 0.1)
				(type default)
			)
			(layer "B.Fab")
		)
		(fp_line
			(start -0.120396 0.3048)
			(end -0.120396 0.2794)
			(stroke
				(width 0.1)
				(type default)
			)
			(layer "B.Fab")
		)
		(fp_line
			(start -0.67945 0.3048)
			(end -0.120396 0.3048)
			(stroke
				(width 0.1)
				(type default)
			)
			(layer "B.Fab")
		)
		(pad "1" smd circle
			(at 0.40005 0 270)
			(size 0 0)
			(layers "B.Cu" "B.Mask" "B.Paste")
			(net "P1V2_STBY_MVDD_CK")
		)
		(pad "2" smd circle
			(at -0.40005 0 270)
			(size 0 0)
			(layers "B.Cu" "B.Mask" "B.Paste")
			(net "GND")
		)
	)
	(footprint ""
		(layer "B.Cu")
		(at 24.384 -94.234 180)
		(property "Reference" "C195"
			(at 0 0 0)
			(layer "B.SilkS")
			(hide yes)
			(effects
				(font
					(size 1.27 1.27)
				)
				(justify mirror)
			)
		)
		(property "Value" ""
			(at 0 0 0)
			(layer "B.Fab")
			(effects
				(font
					(size 1.27 1.27)
				)
				(justify mirror)
			)
		)
		(duplicate_pad_numbers_are_jumpers no)
		(fp_line
			(start 0.69215 0.2921)
			(end 0.69215 -0.2921)
			(stroke
				(width 0.1524)
				(type default)
			)
			(layer "B.SilkS")
		)
		(fp_line
			(start 0.69215 -0.2921)
			(end -0.69215 -0.2921)
			(stroke
				(width 0.1524)
				(type default)
			)
			(layer "B.SilkS")
		)
		(fp_line
			(start -0.69215 0.2921)
			(end 0.69215 0.2921)
			(stroke
				(width 0.1524)
				(type default)
			)
			(layer "B.SilkS")
		)
		(fp_line
			(start -0.69215 -0.2921)
			(end -0.69215 0.2921)
			(stroke
				(width 0.1524)
				(type default)
			)
			(layer "B.SilkS")
		)
		(fp_line
			(start 0.51435 0.2794)
			(end 0.51435 -0.2794)
			(stroke
				(width 0.1)
				(type default)
			)
			(layer "B.Fab")
		)
		(fp_line
			(start 0.51435 -0.2794)
			(end -0.51435 -0.2794)
			(stroke
				(width 0.1)
				(type default)
			)
			(layer "B.Fab")
		)
		(fp_line
			(start -0.51435 0.2794)
			(end 0.51435 0.2794)
			(stroke
				(width 0.1)
				(type default)
			)
			(layer "B.Fab")
		)
		(fp_line
			(start -0.51435 -0.2794)
			(end -0.51435 0.2794)
			(stroke
				(width 0.1)
				(type default)
			)
			(layer "B.Fab")
		)
		(pad "1" smd circle
			(at 0.40005 0)
			(size 0 0)
			(layers "B.Cu" "B.Mask" "B.Paste")
			(net "VCCIO4")
		)
		(pad "2" smd circle
			(at -0.40005 0)
			(size 0 0)
			(layers "B.Cu" "B.Mask" "B.Paste")
			(net "GND")
		)
		(zone
			(layer "B.Cu")
			(hatch none 0.5)
			(connect_pads
				(clearance 0)
			)
			(min_thickness 0.25)
			(keepout
				(tracks not_allowed)
				(vias allowed)
				(pads allowed)
				(copperpour not_allowed)
				(footprints allowed)
			)
			(placement
				(enabled no)
				(sheetname "")
			)
			(fill
				(thermal_gap 0.5)
				(thermal_bridge_width 0.5)
				(island_removal_mode 0)
			)
			(polygon
				(pts
					(xy 24.1935 -94.32163) (xy 24.28494 -94.379796) (xy 24.48433 -94.379796) (xy 24.5745 -94.32163)
					(xy 24.5745 -94.14637) (xy 24.48433 -94.08795) (xy 24.28494 -94.08795) (xy 24.1935 -94.146116)
				)
			)
		)
	)
	(footprint ""
		(layer "B.Cu")
		(at 63.964058 -71.317612)
		(property "Reference" "R120"
			(at 0 0 0)
			(layer "B.SilkS")
			(hide yes)
			(effects
				(font
					(size 1.27 1.27)
				)
				(justify mirror)
			)
		)
		(property "Value" ""
			(at 0 0 0)
			(layer "B.Fab")
			(effects
				(font
					(size 1.27 1.27)
				)
				(justify mirror)
			)
		)
		(duplicate_pad_numbers_are_jumpers no)
		(fp_line
			(start -0.7874 -0.4064)
			(end -0.7874 0.4064)
			(stroke
				(width 0.1524)
				(type default)
			)
			(layer "B.SilkS")
		)
		(fp_line
			(start -0.7874 0.4064)
			(end 0.7874 0.4064)
			(stroke
				(width 0.1524)
				(type default)
			)
			(layer "B.SilkS")
		)
		(fp_line
			(start 0.7874 -0.4064)
			(end -0.7874 -0.4064)
			(stroke
				(width 0.1524)
				(type default)
			)
			(layer "B.SilkS")
		)
		(fp_line
			(start 0.7874 0.4064)
			(end 0.7874 -0.4064)
			(stroke
				(width 0.1524)
				(type default)
			)
			(layer "B.SilkS")
		)
		(fp_line
			(start -0.67945 -0.3048)
			(end -0.67945 0.3048)
			(stroke
				(width 0.1)
				(type default)
			)
			(layer "B.Fab")
		)
		(fp_line
			(start -0.67945 0.3048)
			(end -0.120396 0.3048)
			(stroke
				(width 0.1)
				(type default)
			)
			(layer "B.Fab")
		)
		(fp_line
			(start -0.12065 -0.3048)
			(end -0.67945 -0.3048)
			(stroke
				(width 0.1)
				(type default)
			)
			(layer "B.Fab")
		)
		(fp_line
			(start -0.12065 -0.2794)
			(end -0.12065 -0.3048)
			(stroke
				(width 0.1)
				(type default)
			)
			(layer "B.Fab")
		)
		(fp_line
			(start -0.120396 0.2794)
			(end 0.12065 0.2794)
			(stroke
				(width 0.1)
				(type default)
			)
			(layer "B.Fab")
		)
		(fp_line
			(start -0.120396 0.3048)
			(end -0.120396 0.2794)
			(stroke
				(width 0.1)
				(type default)
			)
			(layer "B.Fab")
		)
		(fp_line
			(start 0.12065 -0.305054)
			(end 0.12065 -0.2794)
			(stroke
				(width 0.1)
				(type default)
			)
			(layer "B.Fab")
		)
		(fp_line
			(start 0.12065 -0.2794)
			(end -0.12065 -0.2794)
			(stroke
				(width 0.1)
				(type default)
			)
			(layer "B.Fab")
		)
		(fp_line
			(start 0.12065 0.2794)
			(end 0.12065 0.3048)
			(stroke
				(width 0.1)
				(type default)
			)
			(layer "B.Fab")
		)
		(fp_line
			(start 0.12065 0.3048)
			(end 0.67945 0.3048)
			(stroke
				(width 0.1)
				(type default)
			)
			(layer "B.Fab")
		)
		(fp_line
			(start 0.67945 -0.305054)
			(end 0.12065 -0.305054)
			(stroke
				(width 0.1)
				(type default)
			)
			(layer "B.Fab")
		)
		(fp_line
			(start 0.67945 0.3048)
			(end 0.67945 -0.305054)
			(stroke
				(width 0.1)
				(type default)
			)
			(layer "B.Fab")
		)
		(pad "1" smd circle
			(at 0.40005 0 180)
			(size 0 0)
			(layers "B.Cu" "B.Mask" "B.Paste")
			(net "RST_BMC_LPC_ESPI_N")
		)
		(pad "2" smd circle
			(at -0.40005 0 180)
			(size 0 0)
			(layers "B.Cu" "B.Mask" "B.Paste")
			(net "RST_ESPI_LPC_BMC_N")
		)
	)
	(footprint ""
		(layer "B.Cu")
		(at 52.024534 -54.93258 180)
		(property "Reference" "C94"
			(at 0 0 0)
			(layer "B.SilkS")
			(hide yes)
			(effects
				(font
					(size 1.27 1.27)
				)
				(justify mirror)
			)
		)
		(property "Value" ""
			(at 0 0 0)
			(layer "B.Fab")
			(effects
				(font
					(size 1.27 1.27)
				)
				(justify mirror)
			)
		)
		(duplicate_pad_numbers_are_jumpers no)
		(fp_line
			(start 0.7874 0.4064)
			(end 0.7874 -0.4064)
			(stroke
				(width 0.1524)
				(type default)
			)
			(layer "B.SilkS")
		)
		(fp_line
			(start 0.7874 -0.4064)
			(end -0.7874 -0.4064)
			(stroke
				(width 0.1524)
				(type default)
			)
			(layer "B.SilkS")
		)
		(fp_line
			(start -0.7874 0.4064)
			(end 0.7874 0.4064)
			(stroke
				(width 0.1524)
				(type default)
			)
			(layer "B.SilkS")
		)
		(fp_line
			(start -0.7874 -0.4064)
			(end -0.7874 0.4064)
			(stroke
				(width 0.1524)
				(type default)
			)
			(layer "B.SilkS")
		)
		(fp_line
			(start 0.67945 0.3048)
			(end 0.67945 -0.305054)
			(stroke
				(width 0.1)
				(type default)
			)
			(layer "B.Fab")
		)
		(fp_line
			(start 0.67945 -0.305054)
			(end 0.12065 -0.305054)
			(stroke
				(width 0.1)
				(type default)
			)
			(layer "B.Fab")
		)
		(fp_line
			(start 0.12065 0.3048)
			(end 0.67945 0.3048)
			(stroke
				(width 0.1)
				(type default)
			)
			(layer "B.Fab")
		)
		(fp_line
			(start 0.12065 0.2794)
			(end 0.12065 0.3048)
			(stroke
				(width 0.1)
				(type default)
			)
			(layer "B.Fab")
		)
		(fp_line
			(start 0.12065 -0.2794)
			(end -0.12065 -0.2794)
			(stroke
				(width 0.1)
				(type default)
			)
			(layer "B.Fab")
		)
		(fp_line
			(start 0.12065 -0.305054)
			(end 0.12065 -0.2794)
			(stroke
				(width 0.1)
				(type default)
			)
			(layer "B.Fab")
		)
		(fp_line
			(start -0.120396 0.3048)
			(end -0.120396 0.2794)
			(stroke
				(width 0.1)
				(type default)
			)
			(layer "B.Fab")
		)
		(fp_line
			(start -0.120396 0.2794)
			(end 0.12065 0.2794)
			(stroke
				(width 0.1)
				(type default)
			)
			(layer "B.Fab")
		)
		(fp_line
			(start -0.12065 -0.2794)
			(end -0.12065 -0.3048)
			(stroke
				(width 0.1)
				(type default)
			)
			(layer "B.Fab")
		)
		(fp_line
			(start -0.12065 -0.3048)
			(end -0.67945 -0.3048)
			(stroke
				(width 0.1)
				(type default)
			)
			(layer "B.Fab")
		)
		(fp_line
			(start -0.67945 0.3048)
			(end -0.120396 0.3048)
			(stroke
				(width 0.1)
				(type default)
			)
			(layer "B.Fab")
		)
		(fp_line
			(start -0.67945 -0.3048)
			(end -0.67945 0.3048)
			(stroke
				(width 0.1)
				(type default)
			)
			(layer "B.Fab")
		)
		(pad "1" smd circle
			(at 0.40005 0)
			(size 0 0)
			(layers "B.Cu" "B.Mask" "B.Paste")
			(net "P3V3_AUX")
		)
		(pad "2" smd circle
			(at -0.40005 0)
			(size 0 0)
			(layers "B.Cu" "B.Mask" "B.Paste")
			(net "GND")
		)
	)
	(footprint ""
		(layer "B.Cu")
		(at 17.653 -60.325 90)
		(property "Reference" "C158"
			(at 0 0 90)
			(layer "B.SilkS")
			(hide yes)
			(effects
				(font
					(size 1.27 1.27)
				)
				(justify mirror)
			)
		)
		(property "Value" ""
			(at 0 0 90)
			(layer "B.Fab")
			(effects
				(font
					(size 1.27 1.27)
				)
				(justify mirror)
			)
		)
		(duplicate_pad_numbers_are_jumpers no)
		(fp_line
			(start 0.7874 -0.4064)
			(end -0.7874 -0.4064)
			(stroke
				(width 0.1524)
				(type default)
			)
			(layer "B.SilkS")
		)
		(fp_line
			(start -0.7874 -0.4064)
			(end -0.7874 0.4064)
			(stroke
				(width 0.1524)
				(type default)
			)
			(layer "B.SilkS")
		)
		(fp_line
			(start 0.7874 0.4064)
			(end 0.7874 -0.4064)
			(stroke
				(width 0.1524)
				(type default)
			)
			(layer "B.SilkS")
		)
		(fp_line
			(start -0.7874 0.4064)
			(end 0.7874 0.4064)
			(stroke
				(width 0.1524)
				(type default)
			)
			(layer "B.SilkS")
		)
		(fp_line
			(start 0.67945 -0.305054)
			(end 0.12065 -0.305054)
			(stroke
				(width 0.1)
				(type default)
			)
			(layer "B.Fab")
		)
		(fp_line
			(start 0.12065 -0.305054)
			(end 0.12065 -0.2794)
			(stroke
				(width 0.1)
				(type default)
			)
			(layer "B.Fab")
		)
		(fp_line
			(start -0.12065 -0.3048)
			(end -0.67945 -0.3048)
			(stroke
				(width 0.1)
				(type default)
			)
			(layer "B.Fab")
		)
		(fp_line
			(start -0.67945 -0.3048)
			(end -0.67945 0.3048)
			(stroke
				(width 0.1)
				(type default)
			)
			(layer "B.Fab")
		)
		(fp_line
			(start 0.12065 -0.2794)
			(end -0.12065 -0.2794)
			(stroke
				(width 0.1)
				(type default)
			)
			(layer "B.Fab")
		)
		(fp_line
			(start -0.12065 -0.2794)
			(end -0.12065 -0.3048)
			(stroke
				(width 0.1)
				(type default)
			)
			(layer "B.Fab")
		)
		(fp_line
			(start 0.12065 0.2794)
			(end 0.12065 0.3048)
			(stroke
				(width 0.1)
				(type default)
			)
			(layer "B.Fab")
		)
		(fp_line
			(start -0.120396 0.2794)
			(end 0.12065 0.2794)
			(stroke
				(width 0.1)
				(type default)
			)
			(layer "B.Fab")
		)
		(fp_line
			(start 0.67945 0.3048)
			(end 0.67945 -0.305054)
			(stroke
				(width 0.1)
				(type default)
			)
			(layer "B.Fab")
		)
		(fp_line
			(start 0.12065 0.3048)
			(end 0.67945 0.3048)
			(stroke
				(width 0.1)
				(type default)
			)
			(layer "B.Fab")
		)
		(fp_line
			(start -0.120396 0.3048)
			(end -0.120396 0.2794)
			(stroke
				(width 0.1)
				(type default)
			)
			(layer "B.Fab")
		)
		(fp_line
			(start -0.67945 0.3048)
			(end -0.120396 0.3048)
			(stroke
				(width 0.1)
				(type default)
			)
			(layer "B.Fab")
		)
		(pad "1" smd circle
			(at 0.40005 0 270)
			(size 0 0)
			(layers "B.Cu" "B.Mask" "B.Paste")
			(net "P3V3_AUX")
		)
		(pad "2" smd circle
			(at -0.40005 0 270)
			(size 0 0)
			(layers "B.Cu" "B.Mask" "B.Paste")
			(net "GND")
		)
	)
	(footprint ""
		(layer "B.Cu")
		(at 49.461166 -62.116462 90)
		(property "Reference" "R846"
			(at 0 0 90)
			(layer "B.SilkS")
			(hide yes)
			(effects
				(font
					(size 1.27 1.27)
				)
				(justify mirror)
			)
		)
		(property "Value" ""
			(at 0 0 90)
			(layer "B.Fab")
			(effects
				(font
					(size 1.27 1.27)
				)
				(justify mirror)
			)
		)
		(duplicate_pad_numbers_are_jumpers no)
		(fp_line
			(start 0.7874 -0.4064)
			(end -0.7874 -0.4064)
			(stroke
				(width 0.1524)
				(type default)
			)
			(layer "B.SilkS")
		)
		(fp_line
			(start -0.7874 -0.4064)
			(end -0.7874 0.4064)
			(stroke
				(width 0.1524)
				(type default)
			)
			(layer "B.SilkS")
		)
		(fp_line
			(start 0.7874 0.4064)
			(end 0.7874 -0.4064)
			(stroke
				(width 0.1524)
				(type default)
			)
			(layer "B.SilkS")
		)
		(fp_line
			(start -0.7874 0.4064)
			(end 0.7874 0.4064)
			(stroke
				(width 0.1524)
				(type default)
			)
			(layer "B.SilkS")
		)
		(fp_line
			(start 0.67945 -0.305054)
			(end 0.12065 -0.305054)
			(stroke
				(width 0.1)
				(type default)
			)
			(layer "B.Fab")
		)
		(fp_line
			(start 0.12065 -0.305054)
			(end 0.12065 -0.2794)
			(stroke
				(width 0.1)
				(type default)
			)
			(layer "B.Fab")
		)
		(fp_line
			(start -0.12065 -0.3048)
			(end -0.67945 -0.3048)
			(stroke
				(width 0.1)
				(type default)
			)
			(layer "B.Fab")
		)
		(fp_line
			(start -0.67945 -0.3048)
			(end -0.67945 0.3048)
			(stroke
				(width 0.1)
				(type default)
			)
			(layer "B.Fab")
		)
		(fp_line
			(start 0.12065 -0.2794)
			(end -0.12065 -0.2794)
			(stroke
				(width 0.1)
				(type default)
			)
			(layer "B.Fab")
		)
		(fp_line
			(start -0.12065 -0.2794)
			(end -0.12065 -0.3048)
			(stroke
				(width 0.1)
				(type default)
			)
			(layer "B.Fab")
		)
		(fp_line
			(start 0.12065 0.2794)
			(end 0.12065 0.3048)
			(stroke
				(width 0.1)
				(type default)
			)
			(layer "B.Fab")
		)
		(fp_line
			(start -0.120396 0.2794)
			(end 0.12065 0.2794)
			(stroke
				(width 0.1)
				(type default)
			)
			(layer "B.Fab")
		)
		(fp_line
			(start 0.67945 0.3048)
			(end 0.67945 -0.305054)
			(stroke
				(width 0.1)
				(type default)
			)
			(layer "B.Fab")
		)
		(fp_line
			(start 0.12065 0.3048)
			(end 0.67945 0.3048)
			(stroke
				(width 0.1)
				(type default)
			)
			(layer "B.Fab")
		)
		(fp_line
			(start -0.120396 0.3048)
			(end -0.120396 0.2794)
			(stroke
				(width 0.1)
				(type default)
			)
			(layer "B.Fab")
		)
		(fp_line
			(start -0.67945 0.3048)
			(end -0.120396 0.3048)
			(stroke
				(width 0.1)
				(type default)
			)
			(layer "B.Fab")
		)
		(pad "1" smd circle
			(at 0.40005 0 270)
			(size 0 0)
			(layers "B.Cu" "B.Mask" "B.Paste")
			(net "P3V3_AUX")
		)
		(pad "2" smd circle
			(at -0.40005 0 270)
			(size 0 0)
			(layers "B.Cu" "B.Mask" "B.Paste")
			(net "FM_BMC_EN_DET_R")
		)
	)
)
